# TIMECARD (Time Appliance Project (Time Card)) — schematic netlist excerpt (pin names and nets, part order shuffled) for the footprints in the layout excerpt that follows; sources: Cadence DE-HDL packaged netlist, KiCad conversion of R4006-B0001-02_R01.brd

R415  RESISTOR  1KOHM 1%  pkg SMC_0402R_H016  page 17 : \1\ = UNNAMED_6_LM75BDPTSSOP8_I81_A1 ; \2\ = SG
C121  CAPACITOR  0.1UF 10V 10%  pkg SMC_0402R_H022  page 14 : \1\ = XP1R0V_FPGA_VCCINT ; \2\ = SG

(kicad_pcb
	(version 20260206)
	(generator "pcbnew")
	(generator_version "10.0")
	(general
		(thickness 1.6)
		(legacy_teardrops no)
	)
	(paper "A4")
	(title_block
		(title "timecard-production-celestica-r4006 — R4006-B0001-02_R01.brd")
		(comment 1 "Time Appliance Project (Time Card) / footprints 704-705 of 1113")
	)
	(layers
		(0 "F.Cu" signal "TOP")
		(4 "In1.Cu" signal "L02_GND1")
		(6 "In2.Cu" signal "L03_SIG1")
		(8 "In3.Cu" signal "L04_GND2")
		(10 "In4.Cu" signal "L05_VCC1")
		(12 "In5.Cu" signal "L06_VCC2")
		(14 "In6.Cu" signal "L07_GND3")
		(16 "In7.Cu" signal "L08_SIG2")
		(18 "In8.Cu" signal "L09_GND4")
		(2 "B.Cu" signal "BOTTOM")
		(9 "F.Adhes" user "F.Adhesive")
		(11 "B.Adhes" user "B.Adhesive")
		(13 "F.Paste" user "Package Geometry/Pastemask Top")
		(15 "B.Paste" user "Package Geometry/Pastemask Bottom")
		(5 "F.SilkS" user "Ref Des/Silkscreen Top")
		(7 "B.SilkS" user "Ref Des/Silkscreen Bottom")
		(1 "F.Mask" user "Board Geometry/Soldermask Top")
		(3 "B.Mask" user "Board Geometry/Soldermask Bottom")
		(17 "Dwgs.User" user "User.Drawings")
		(19 "Cmts.User" user "User.Comments")
		(21 "Eco1.User" user "User.Eco1")
		(23 "Eco2.User" user "User.Eco2")
		(25 "Edge.Cuts" user "Board Geometry/Outline")
		(27 "Margin" user)
		(31 "F.CrtYd" user "Package Geometry/Place Bound Top")
		(29 "B.CrtYd" user "Package Geometry/Place Bound Bottom")
		(35 "F.Fab" user "Ref Des/Assembly Top")
		(33 "B.Fab" user "Ref Des/Assembly Bottom")
	)
	(footprint ""
		(layer "B.Cu")
		(at 105.847134 -40.323008 90)
		(property "Reference" "C121"
			(at -1.143508 -41.383204 270)
			(unlocked yes)
			(layer "B.SilkS")
			(effects
				(font
					(size 0.635 0.4064)
					(thickness 0.1524)
				)
				(justify mirror)
			)
		)
		(property "Value" "VAL*"
			(at 0 3.718306 90)
			(unlocked yes)
			(layer "B.Fab")
			(hide yes)
			(effects
				(font
					(size 0.7874 0.5842)
					(thickness 0.127)
				)
				(justify mirror)
			)
		)
		(property "Device Type" "CAPACITOR-G105-0B104-CK,0.1UF,A"
			(at 0 1.432306 90)
			(unlocked yes)
			(layer "B.Fab")
			(hide yes)
			(effects
				(font
					(size 0.7874 0.5842)
					(thickness 0.127)
				)
				(justify mirror)
			)
		)
		(property "User Part Number" "PARTNUM*"
			(at 0 2.575306 90)
			(unlocked yes)
			(layer "Cmts.User")
			(hide yes)
			(effects
				(font
					(size 0.7874 0.5842)
					(thickness 0.127)
				)
				(justify mirror)
			)
		)
		(property "Tolerance" "TOL*"
			(at 0 4.861306 90)
			(unlocked yes)
			(layer "Cmts.User")
			(hide yes)
			(effects
				(font
					(size 0.7874 0.5842)
					(thickness 0.127)
				)
				(justify mirror)
			)
		)
		(duplicate_pad_numbers_are_jumpers no)
		(fp_line
			(start 0.970026 -0.4699)
			(end -0.970026 -0.4699)
			(stroke
				(width 0.1)
				(type default)
			)
			(layer "B.SilkS")
		)
		(fp_line
			(start -0.970026 -0.4699)
			(end -0.970026 0.4699)
			(stroke
				(width 0.1)
				(type default)
			)
			(layer "B.SilkS")
		)
		(fp_line
			(start 0.970026 0.4699)
			(end 0.970026 -0.4699)
			(stroke
				(width 0.1)
				(type default)
			)
			(layer "B.SilkS")
		)
		(fp_line
			(start -0.970026 0.4699)
			(end 0.970026 0.4699)
			(stroke
				(width 0.1)
				(type default)
			)
			(layer "B.SilkS")
		)
		(fp_poly
			(pts
				(xy 0.970026 0.4699) (xy -0.970026 0.4699) (xy -0.970026 -0.4699) (xy 0.970026 -0.4699)
			)
			(stroke
				(width 0)
				(type default)
			)
			(fill no)
			(layer "B.CrtYd")
		)
		(fp_line
			(start 0.508 -0.3048)
			(end -0.508 -0.3048)
			(stroke
				(width 0.1)
				(type default)
			)
			(layer "B.Fab")
		)
		(fp_line
			(start -0.508 -0.3048)
			(end -0.508 0.3048)
			(stroke
				(width 0.1)
				(type default)
			)
			(layer "B.Fab")
		)
		(fp_line
			(start 0.508 0.3048)
			(end 0.508 -0.3048)
			(stroke
				(width 0.1)
				(type default)
			)
			(layer "B.Fab")
		)
		(fp_line
			(start -0.508 0.3048)
			(end 0.508 0.3048)
			(stroke
				(width 0.1)
				(type default)
			)
			(layer "B.Fab")
		)
		(pad "1" smd circle
			(at 0.500126 0 270)
			(size 0.635 0.635)
			(layers "B.Cu" "B.Mask" "B.Paste")
			(net "XP1R0V_FPGA_VCCINT")
		)
		(pad "2" smd circle
			(at -0.500126 0 270)
			(size 0.635 0.635)
			(layers "B.Cu" "B.Mask" "B.Paste")
			(net "SG")
		)
	)
	(footprint ""
		(layer "B.Cu")
		(at 162.56 -25.908 180)
		(property "Reference" "R415"
			(at 0.508 2.62763 0)
			(unlocked yes)
			(layer "B.SilkS")
			(effects
				(font
					(size 0.7874 0.5842)
					(thickness 0.1524)
				)
				(justify mirror)
			)
		)
		(property "Value" "VAL*"
			(at -0.02032 2.13233 180)
			(unlocked yes)
			(layer "B.Fab")
			(hide yes)
			(effects
				(font
					(size 0.7874 0.5842)
					(thickness 0.1524)
				)
				(justify mirror)
			)
		)
		(property "Tolerance" "TOL*"
			(at -0.044704 3.05435 180)
			(unlocked yes)
			(layer "Cmts.User")
			(hide yes)
			(effects
				(font
					(size 0.7874 0.5842)
					(thickness 0.1524)
				)
				(justify mirror)
			)
		)
		(property "User Part Number" "PARTNUM*"
			(at -0.02032 4.024884 180)
			(unlocked yes)
			(layer "Cmts.User")
			(hide yes)
			(effects
				(font
					(size 0.7874 0.5842)
					(thickness 0.1524)
				)
				(justify mirror)
			)
		)
		(property "Device Type" "RESISTOR-G155-11001-01,1KOHM,1%"
			(at -0.008382 1.210564 180)
			(unlocked yes)
			(layer "B.Fab")
			(hide yes)
			(effects
				(font
					(size 0.7874 0.5842)
					(thickness 0.1524)
				)
				(justify mirror)
			)
		)
		(duplicate_pad_numbers_are_jumpers no)
		(fp_line
			(start 1.143 0.5588)
			(end -1.143 0.5588)
			(stroke
				(width 0.1)
				(type default)
			)
			(layer "B.SilkS")
		)
		(fp_line
			(start 1.143 -0.5588)
			(end 1.143 0.5588)
			(stroke
				(width 0.1)
				(type default)
			)
			(layer "B.SilkS")
		)
		(fp_line
			(start -1.143 0.5588)
			(end -1.143 -0.5588)
			(stroke
				(width 0.1)
				(type default)
			)
			(layer "B.SilkS")
		)
		(fp_line
			(start -1.143 -0.5588)
			(end 1.143 -0.5588)
			(stroke
				(width 0.1)
				(type default)
			)
			(layer "B.SilkS")
		)
		(fp_rect
			(start 1.143 -0.5588)
			(end -1.143 0.5588)
			(stroke
				(width 0)
				(type default)
			)
			(fill no)
			(layer "B.CrtYd")
		)
		(fp_line
			(start 0.508 0.3048)
			(end -0.508 0.3048)
			(stroke
				(width 0.1)
				(type default)
			)
			(layer "B.Fab")
		)
		(fp_line
			(start 0.508 -0.3048)
			(end 0.508 0.3048)
			(stroke
				(width 0.1)
				(type default)
			)
			(layer "B.Fab")
		)
		(fp_line
			(start -0.508 0.3048)
			(end -0.508 -0.3048)
			(stroke
				(width 0.1)
				(type default)
			)
			(layer "B.Fab")
		)
		(fp_line
			(start -0.508 -0.3048)
			(end 0.508 -0.3048)
			(stroke
				(width 0.1)
				(type default)
			)
			(layer "B.Fab")
		)
		(pad "1" smd rect
			(at 0.5334 0)
			(size 0.7112 0.6096)
			(layers "B.Cu" "B.Mask" "B.Paste")
			(net "UNNAMED_6_LM75BDPTSSOP8_I81_A1")
		)
		(pad "2" smd rect
			(at -0.5334 0)
			(size 0.7112 0.6096)
			(layers "B.Cu" "B.Mask" "B.Paste")
			(net "SG")
		)
		(zone
			(layer "B.Cu")
			(hatch none 0.5)
			(connect_pads
				(clearance 0)
			)
			(min_thickness 0.25)
			(keepout
				(tracks allowed)
				(vias not_allowed)
				(pads allowed)
				(copperpour not_allowed)
				(footprints allowed)
			)
			(placement
				(enabled no)
				(sheetname "")
			)
			(fill
				(thermal_gap 0.5)
				(thermal_bridge_width 0.5)
				(island_removal_mode 0)
			)
			(polygon
				(pts
					(xy 162.4838 -25.6032) (xy 162.6362 -25.6032) (xy 162.6362 -26.2128) (xy 162.4838 -26.2128)
				)
			)
		)
		(zone
			(layer "B.Cu")
			(hatch none 0.5)
			(connect_pads
				(clearance 0)
			)
			(min_thickness 0.25)
			(keepout
				(tracks not_allowed)
				(vias allowed)
				(pads allowed)
				(copperpour not_allowed)
				(footprints allowed)
			)
			(placement
				(enabled no)
				(sheetname "")
			)
			(fill
				(thermal_gap 0.5)
				(thermal_bridge_width 0.5)
				(island_removal_mode 0)
			)
			(polygon
				(pts
					(xy 162.4838 -25.6032) (xy 162.6362 -25.6032) (xy 162.6362 -26.2128) (xy 162.4838 -26.2128)
				)
			)
		)
	)
)
